(kicad_pcb
	(version 20260206)
	(generator "pcbnew")
	(generator_version "10.0")
	(general
		(thickness 1.6)
		(legacy_teardrops no)
	)
	(paper "A4")
	(title_block
		(title "03242023_DA0F0TMBIJ0_F0T_Motherboard_J_brd_V01_OCP.brd")
		(comment 1 "Grand Teton / footprints 3130-3132 of 6105")
	)
	(layers
		(0 "F.Cu" signal "TOP")
		(4 "In1.Cu" signal "GND")
		(6 "In2.Cu" signal "IN1")
		(8 "In3.Cu" signal "GND1")
		(10 "In4.Cu" signal "IN2")
		(12 "In5.Cu" signal "GND2")
		(14 "In6.Cu" signal "IN3")
		(16 "In7.Cu" signal "GND3")
		(18 "In8.Cu" signal "VCC")
		(20 "In9.Cu" signal "VCC1")
		(22 "In10.Cu" signal "GND4")
		(24 "In11.Cu" signal "IN4")
		(26 "In12.Cu" signal "GND5")
		(28 "In13.Cu" signal "IN5")
		(30 "In14.Cu" signal "GND6")
		(32 "In15.Cu" signal "IN6")
		(34 "In16.Cu" signal "GND7")
		(2 "B.Cu" signal "BOTTOM")
		(9 "F.Adhes" user "F.Adhesive")
		(11 "B.Adhes" user "B.Adhesive")
		(13 "F.Paste" user "Package Geometry/Pastemask Top")
		(15 "B.Paste" user "Package Geometry/Pastemask Bottom")
		(5 "F.SilkS" user "Ref Des/Silkscreen Top")
		(7 "B.SilkS" user "Ref Des/Silkscreen Bottom")
		(1 "F.Mask" user "Board Geometry/Soldermask Top")
		(3 "B.Mask" user "Board Geometry/Soldermask Bottom")
		(17 "Dwgs.User" user "User.Drawings")
		(19 "Cmts.User" user "User.Comments")
		(21 "Eco1.User" user "User.Eco1")
		(23 "Eco2.User" user "User.Eco2")
		(25 "Edge.Cuts" user "Board Geometry/Outline")
		(27 "Margin" user)
		(31 "F.CrtYd" user "Package Geometry/Place Bound Top")
		(29 "B.CrtYd" user "Package Geometry/Place Bound Bottom")
		(35 "F.Fab" user "Ref Des/Assembly Top")
		(33 "B.Fab" user "Ref Des/Assembly Bottom")
	)
	(footprint ""
		(layer "F.Cu")
		(at 429.48225 -362.18368 -90)
		(property "Reference" "PC1175_P0_3"
			(at 0 0 270)
			(layer "F.SilkS")
			(hide yes)
			(effects
				(font
					(size 1.27 1.27)
				)
			)
		)
		(property "Value" ""
			(at 0 0 270)
			(layer "F.Fab")
			(effects
				(font
					(size 1.27 1.27)
				)
			)
		)
		(duplicate_pad_numbers_are_jumpers no)
		(fp_line
			(start -0.7874 0.4064)
			(end -0.7874 -0.4064)
			(stroke
				(width 0.1524)
				(type default)
			)
			(layer "F.SilkS")
		)
		(fp_line
			(start 0.7874 0.4064)
			(end -0.7874 0.4064)
			(stroke
				(width 0.1524)
				(type default)
			)
			(layer "F.SilkS")
		)
		(fp_line
			(start -0.7874 -0.4064)
			(end 0.7874 -0.4064)
			(stroke
				(width 0.1524)
				(type default)
			)
			(layer "F.SilkS")
		)
		(fp_line
			(start 0.7874 -0.4064)
			(end 0.7874 0.4064)
			(stroke
				(width 0.1524)
				(type default)
			)
			(layer "F.SilkS")
		)
		(fp_line
			(start -0.67945 0.3048)
			(end -0.67945 -0.305054)
			(stroke
				(width 0.1)
				(type default)
			)
			(layer "F.Fab")
		)
		(fp_line
			(start -0.12065 0.3048)
			(end -0.67945 0.3048)
			(stroke
				(width 0.1)
				(type default)
			)
			(layer "F.Fab")
		)
		(fp_line
			(start 0.120396 0.3048)
			(end 0.120396 0.2794)
			(stroke
				(width 0.1)
				(type default)
			)
			(layer "F.Fab")
		)
		(fp_line
			(start 0.67945 0.3048)
			(end 0.120396 0.3048)
			(stroke
				(width 0.1)
				(type default)
			)
			(layer "F.Fab")
		)
		(fp_line
			(start -0.12065 0.2794)
			(end -0.12065 0.3048)
			(stroke
				(width 0.1)
				(type default)
			)
			(layer "F.Fab")
		)
		(fp_line
			(start 0.120396 0.2794)
			(end -0.12065 0.2794)
			(stroke
				(width 0.1)
				(type default)
			)
			(layer "F.Fab")
		)
		(fp_line
			(start -0.12065 -0.2794)
			(end 0.12065 -0.2794)
			(stroke
				(width 0.1)
				(type default)
			)
			(layer "F.Fab")
		)
		(fp_line
			(start 0.12065 -0.2794)
			(end 0.12065 -0.3048)
			(stroke
				(width 0.1)
				(type default)
			)
			(layer "F.Fab")
		)
		(fp_line
			(start 0.12065 -0.3048)
			(end 0.67945 -0.3048)
			(stroke
				(width 0.1)
				(type default)
			)
			(layer "F.Fab")
		)
		(fp_line
			(start 0.67945 -0.3048)
			(end 0.67945 0.3048)
			(stroke
				(width 0.1)
				(type default)
			)
			(layer "F.Fab")
		)
		(fp_line
			(start -0.67945 -0.305054)
			(end -0.12065 -0.305054)
			(stroke
				(width 0.1)
				(type default)
			)
			(layer "F.Fab")
		)
		(fp_line
			(start -0.12065 -0.305054)
			(end -0.12065 -0.2794)
			(stroke
				(width 0.1)
				(type default)
			)
			(layer "F.Fab")
		)
		(pad "1" smd circle
			(at -0.40005 0 270)
			(size 0 0)
			(layers "F.Cu" "F.Mask" "F.Paste")
			(net "SW_P12V_PVCCFA_EHV_FIVRA_CPU0_R")
		)
		(pad "2" smd circle
			(at 0.40005 0 270)
			(size 0 0)
			(layers "F.Cu" "F.Mask" "F.Paste")
			(net "GND")
		)
	)
	(footprint ""
		(layer "F.Cu")
		(at 295.72204 -367.357152 -90)
		(property "Reference" "PC1350"
			(at 0 0 270)
			(layer "F.SilkS")
			(hide yes)
			(effects
				(font
					(size 1.27 1.27)
				)
			)
		)
		(property "Value" ""
			(at 0 0 270)
			(layer "F.Fab")
			(effects
				(font
					(size 1.27 1.27)
				)
			)
		)
		(duplicate_pad_numbers_are_jumpers no)
		(fp_line
			(start -0.7874 0.4064)
			(end -0.7874 -0.4064)
			(stroke
				(width 0.1524)
				(type default)
			)
			(layer "F.SilkS")
		)
		(fp_line
			(start 0.7874 0.4064)
			(end -0.7874 0.4064)
			(stroke
				(width 0.1524)
				(type default)
			)
			(layer "F.SilkS")
		)
		(fp_line
			(start -0.7874 -0.4064)
			(end 0.7874 -0.4064)
			(stroke
				(width 0.1524)
				(type default)
			)
			(layer "F.SilkS")
		)
		(fp_line
			(start 0.7874 -0.4064)
			(end 0.7874 0.4064)
			(stroke
				(width 0.1524)
				(type default)
			)
			(layer "F.SilkS")
		)
		(fp_line
			(start -0.67945 0.3048)
			(end -0.67945 -0.305054)
			(stroke
				(width 0.1)
				(type default)
			)
			(layer "F.Fab")
		)
		(fp_line
			(start -0.12065 0.3048)
			(end -0.67945 0.3048)
			(stroke
				(width 0.1)
				(type default)
			)
			(layer "F.Fab")
		)
		(fp_line
			(start 0.120396 0.3048)
			(end 0.120396 0.2794)
			(stroke
				(width 0.1)
				(type default)
			)
			(layer "F.Fab")
		)
		(fp_line
			(start 0.67945 0.3048)
			(end 0.120396 0.3048)
			(stroke
				(width 0.1)
				(type default)
			)
			(layer "F.Fab")
		)
		(fp_line
			(start -0.12065 0.2794)
			(end -0.12065 0.3048)
			(stroke
				(width 0.1)
				(type default)
			)
			(layer "F.Fab")
		)
		(fp_line
			(start 0.120396 0.2794)
			(end -0.12065 0.2794)
			(stroke
				(width 0.1)
				(type default)
			)
			(layer "F.Fab")
		)
		(fp_line
			(start -0.12065 -0.2794)
			(end 0.12065 -0.2794)
			(stroke
				(width 0.1)
				(type default)
			)
			(layer "F.Fab")
		)
		(fp_line
			(start 0.12065 -0.2794)
			(end 0.12065 -0.3048)
			(stroke
				(width 0.1)
				(type default)
			)
			(layer "F.Fab")
		)
		(fp_line
			(start 0.12065 -0.3048)
			(end 0.67945 -0.3048)
			(stroke
				(width 0.1)
				(type default)
			)
			(layer "F.Fab")
		)
		(fp_line
			(start 0.67945 -0.3048)
			(end 0.67945 0.3048)
			(stroke
				(width 0.1)
				(type default)
			)
			(layer "F.Fab")
		)
		(fp_line
			(start -0.67945 -0.305054)
			(end -0.12065 -0.305054)
			(stroke
				(width 0.1)
				(type default)
			)
			(layer "F.Fab")
		)
		(fp_line
			(start -0.12065 -0.305054)
			(end -0.12065 -0.2794)
			(stroke
				(width 0.1)
				(type default)
			)
			(layer "F.Fab")
		)
		(pad "1" smd circle
			(at -0.40005 0 270)
			(size 0 0)
			(layers "F.Cu" "F.Mask" "F.Paste")
			(net "GND")
		)
		(pad "2" smd circle
			(at 0.40005 0 270)
			(size 0 0)
			(layers "F.Cu" "F.Mask" "F.Paste")
			(net "PVCCIN_CPU0_VREF")
		)
	)
	(footprint ""
		(layer "F.Cu")
		(at 46.548294 -17.623536 90)
		(property "Reference" "C828"
			(at 0 0 90)
			(layer "F.SilkS")
			(hide yes)
			(effects
				(font
					(size 1.27 1.27)
				)
			)
		)
		(property "Value" ""
			(at 0 0 90)
			(layer "F.Fab")
			(effects
				(font
					(size 1.27 1.27)
				)
			)
		)
		(duplicate_pad_numbers_are_jumpers no)
		(fp_line
			(start 0.299974 -0.150114)
			(end 0.299974 0.150114)
			(stroke
				(width 0.1)
				(type default)
			)
			(layer "F.Fab")
		)
		(fp_line
			(start -0.299974 -0.150114)
			(end 0.299974 -0.150114)
			(stroke
				(width 0.1)
				(type default)
			)
			(layer "F.Fab")
		)
		(fp_line
			(start 0.299974 0.150114)
			(end -0.299974 0.150114)
			(stroke
				(width 0.1)
				(type default)
			)
			(layer "F.Fab")
		)
		(fp_line
			(start -0.299974 0.150114)
			(end -0.299974 -0.150114)
			(stroke
				(width 0.1)
				(type default)
			)
			(layer "F.Fab")
		)
		(pad "1" smd rect
			(at -0.2667 0 90)
			(size 0.3048 0.381)
			(layers "F.Cu" "F.Mask" "F.Paste")
			(net "P5E_CPU1_PE1_TX_C_DN<4>")
		)
		(pad "2" smd rect
			(at 0.2667 0 90)
			(size 0.3048 0.381)
			(layers "F.Cu" "F.Mask" "F.Paste")
			(net "P5E_CPU1_PE1_TX_DN<4>")
		)
	)
)
